# S9S_MB_2U (Grand Teton) — schematic netlist excerpt (pin names and nets, part order shuffled) for the footprints in the layout excerpt that follows; sources: Cadence DE-HDL packaged netlist, KiCad conversion of 03242023_DA0F0TMBIJ0_F0T_Motherboard_J_brd_V01_OCP.brd

R244  Q_RES  100 1% CHIP  pkg 0402LF  page 121 : A = PVNN_TERM_CPU1 ; B = H_CPU1_PROCHOT_LVC1_N
R3885  Q_RES  49.9 1% CHIP  pkg 0402LF  page 92 : A = I3C_SPD_DDREFGH_CPU0_LVC1_SCL_2 ; B = I3C_SPD_DDREFGH_CPU0_LVC1_SCL

(kicad_pcb
	(version 20260206)
	(generator "pcbnew")
	(generator_version "10.0")
	(general
		(thickness 1.6)
		(legacy_teardrops no)
	)
	(paper "A4")
	(title_block
		(title "03242023_DA0F0TMBIJ0_F0T_Motherboard_J_brd_V01_OCP.brd")
		(comment 1 "Grand Teton / footprints 5928-5929 of 6105")
	)
	(layers
		(0 "F.Cu" signal "TOP")
		(4 "In1.Cu" signal "GND")
		(6 "In2.Cu" signal "IN1")
		(8 "In3.Cu" signal "GND1")
		(10 "In4.Cu" signal "IN2")
		(12 "In5.Cu" signal "GND2")
		(14 "In6.Cu" signal "IN3")
		(16 "In7.Cu" signal "GND3")
		(18 "In8.Cu" signal "VCC")
		(20 "In9.Cu" signal "VCC1")
		(22 "In10.Cu" signal "GND4")
		(24 "In11.Cu" signal "IN4")
		(26 "In12.Cu" signal "GND5")
		(28 "In13.Cu" signal "IN5")
		(30 "In14.Cu" signal "GND6")
		(32 "In15.Cu" signal "IN6")
		(34 "In16.Cu" signal "GND7")
		(2 "B.Cu" signal "BOTTOM")
		(9 "F.Adhes" user "F.Adhesive")
		(11 "B.Adhes" user "B.Adhesive")
		(13 "F.Paste" user "Package Geometry/Pastemask Top")
		(15 "B.Paste" user "Package Geometry/Pastemask Bottom")
		(5 "F.SilkS" user "Ref Des/Silkscreen Top")
		(7 "B.SilkS" user "Ref Des/Silkscreen Bottom")
		(1 "F.Mask" user "Board Geometry/Soldermask Top")
		(3 "B.Mask" user "Board Geometry/Soldermask Bottom")
		(17 "Dwgs.User" user "User.Drawings")
		(19 "Cmts.User" user "User.Comments")
		(21 "Eco1.User" user "User.Eco1")
		(23 "Eco2.User" user "User.Eco2")
		(25 "Edge.Cuts" user "Board Geometry/Outline")
		(27 "Margin" user)
		(31 "F.CrtYd" user "Package Geometry/Place Bound Top")
		(29 "B.CrtYd" user "Package Geometry/Place Bound Bottom")
		(35 "F.Fab" user "Ref Des/Assembly Top")
		(33 "B.Fab" user "Ref Des/Assembly Bottom")
	)
	(footprint ""
		(layer "B.Cu")
		(at 429.391572 -317.39332 90)
		(property "Reference" "R3885"
			(at 0 0 90)
			(layer "B.SilkS")
			(hide yes)
			(effects
				(font
					(size 1.27 1.27)
				)
				(justify mirror)
			)
		)
		(property "Value" ""
			(at 0 0 90)
			(layer "B.Fab")
			(effects
				(font
					(size 1.27 1.27)
				)
				(justify mirror)
			)
		)
		(duplicate_pad_numbers_are_jumpers no)
		(fp_line
			(start 0.7874 -0.4064)
			(end -0.7874 -0.4064)
			(stroke
				(width 0.1524)
				(type default)
			)
			(layer "B.SilkS")
		)
		(fp_line
			(start -0.7874 -0.4064)
			(end -0.7874 0.4064)
			(stroke
				(width 0.1524)
				(type default)
			)
			(layer "B.SilkS")
		)
		(fp_line
			(start 0.7874 0.4064)
			(end 0.7874 -0.4064)
			(stroke
				(width 0.1524)
				(type default)
			)
			(layer "B.SilkS")
		)
		(fp_line
			(start -0.7874 0.4064)
			(end 0.7874 0.4064)
			(stroke
				(width 0.1524)
				(type default)
			)
			(layer "B.SilkS")
		)
		(fp_line
			(start 0.67945 -0.305054)
			(end 0.12065 -0.305054)
			(stroke
				(width 0.1)
				(type default)
			)
			(layer "B.Fab")
		)
		(fp_line
			(start 0.12065 -0.305054)
			(end 0.12065 -0.2794)
			(stroke
				(width 0.1)
				(type default)
			)
			(layer "B.Fab")
		)
		(fp_line
			(start -0.12065 -0.3048)
			(end -0.67945 -0.3048)
			(stroke
				(width 0.1)
				(type default)
			)
			(layer "B.Fab")
		)
		(fp_line
			(start -0.67945 -0.3048)
			(end -0.67945 0.3048)
			(stroke
				(width 0.1)
				(type default)
			)
			(layer "B.Fab")
		)
		(fp_line
			(start 0.12065 -0.2794)
			(end -0.12065 -0.2794)
			(stroke
				(width 0.1)
				(type default)
			)
			(layer "B.Fab")
		)
		(fp_line
			(start -0.12065 -0.2794)
			(end -0.12065 -0.3048)
			(stroke
				(width 0.1)
				(type default)
			)
			(layer "B.Fab")
		)
		(fp_line
			(start 0.12065 0.2794)
			(end 0.12065 0.3048)
			(stroke
				(width 0.1)
				(type default)
			)
			(layer "B.Fab")
		)
		(fp_line
			(start -0.120396 0.2794)
			(end 0.12065 0.2794)
			(stroke
				(width 0.1)
				(type default)
			)
			(layer "B.Fab")
		)
		(fp_line
			(start 0.67945 0.3048)
			(end 0.67945 -0.305054)
			(stroke
				(width 0.1)
				(type default)
			)
			(layer "B.Fab")
		)
		(fp_line
			(start 0.12065 0.3048)
			(end 0.67945 0.3048)
			(stroke
				(width 0.1)
				(type default)
			)
			(layer "B.Fab")
		)
		(fp_line
			(start -0.120396 0.3048)
			(end -0.120396 0.2794)
			(stroke
				(width 0.1)
				(type default)
			)
			(layer "B.Fab")
		)
		(fp_line
			(start -0.67945 0.3048)
			(end -0.120396 0.3048)
			(stroke
				(width 0.1)
				(type default)
			)
			(layer "B.Fab")
		)
		(pad "1" smd circle
			(at 0.40005 0 270)
			(size 0 0)
			(layers "B.Cu" "B.Mask" "B.Paste")
			(net "I3C_SPD_DDREFGH_CPU0_LVC1_SCL_2")
		)
		(pad "2" smd circle
			(at -0.40005 0 270)
			(size 0 0)
			(layers "B.Cu" "B.Mask" "B.Paste")
			(net "I3C_SPD_DDREFGH_CPU0_LVC1_SCL")
		)
	)
	(footprint ""
		(layer "B.Cu")
		(at 80.430624 -185.874152 90)
		(property "Reference" "R244"
			(at 0 0 90)
			(layer "B.SilkS")
			(hide yes)
			(effects
				(font
					(size 1.27 1.27)
				)
				(justify mirror)
			)
		)
		(property "Value" ""
			(at 0 0 90)
			(layer "B.Fab")
			(effects
				(font
					(size 1.27 1.27)
				)
				(justify mirror)
			)
		)
		(duplicate_pad_numbers_are_jumpers no)
		(fp_line
			(start 0.7874 -0.4064)
			(end -0.7874 -0.4064)
			(stroke
				(width 0.1524)
				(type default)
			)
			(layer "B.SilkS")
		)
		(fp_line
			(start -0.7874 -0.4064)
			(end -0.7874 0.4064)
			(stroke
				(width 0.1524)
				(type default)
			)
			(layer "B.SilkS")
		)
		(fp_line
			(start 0.7874 0.4064)
			(end 0.7874 -0.4064)
			(stroke
				(width 0.1524)
				(type default)
			)
			(layer "B.SilkS")
		)
		(fp_line
			(start -0.7874 0.4064)
			(end 0.7874 0.4064)
			(stroke
				(width 0.1524)
				(type default)
			)
			(layer "B.SilkS")
		)
		(fp_line
			(start 0.67945 -0.305054)
			(end 0.12065 -0.305054)
			(stroke
				(width 0.1)
				(type default)
			)
			(layer "B.Fab")
		)
		(fp_line
			(start 0.12065 -0.305054)
			(end 0.12065 -0.2794)
			(stroke
				(width 0.1)
				(type default)
			)
			(layer "B.Fab")
		)
		(fp_line
			(start -0.12065 -0.3048)
			(end -0.67945 -0.3048)
			(stroke
				(width 0.1)
				(type default)
			)
			(layer "B.Fab")
		)
		(fp_line
			(start -0.67945 -0.3048)
			(end -0.67945 0.3048)
			(stroke
				(width 0.1)
				(type default)
			)
			(layer "B.Fab")
		)
		(fp_line
			(start 0.12065 -0.2794)
			(end -0.12065 -0.2794)
			(stroke
				(width 0.1)
				(type default)
			)
			(layer "B.Fab")
		)
		(fp_line
			(start -0.12065 -0.2794)
			(end -0.12065 -0.3048)
			(stroke
				(width 0.1)
				(type default)
			)
			(layer "B.Fab")
		)
		(fp_line
			(start 0.12065 0.2794)
			(end 0.12065 0.3048)
			(stroke
				(width 0.1)
				(type default)
			)
			(layer "B.Fab")
		)
		(fp_line
			(start -0.120396 0.2794)
			(end 0.12065 0.2794)
			(stroke
				(width 0.1)
				(type default)
			)
			(layer "B.Fab")
		)
		(fp_line
			(start 0.67945 0.3048)
			(end 0.67945 -0.305054)
			(stroke
				(width 0.1)
				(type default)
			)
			(layer "B.Fab")
		)
		(fp_line
			(start 0.12065 0.3048)
			(end 0.67945 0.3048)
			(stroke
				(width 0.1)
				(type default)
			)
			(layer "B.Fab")
		)
		(fp_line
			(start -0.120396 0.3048)
			(end -0.120396 0.2794)
			(stroke
				(width 0.1)
				(type default)
			)
			(layer "B.Fab")
		)
		(fp_line
			(start -0.67945 0.3048)
			(end -0.120396 0.3048)
			(stroke
				(width 0.1)
				(type default)
			)
			(layer "B.Fab")
		)
		(pad "1" smd circle
			(at 0.40005 0 270)
			(size 0 0)
			(layers "B.Cu" "B.Mask" "B.Paste")
			(net "PVNN_TERM_CPU1")
		)
		(pad "2" smd circle
			(at -0.40005 0 270)
			(size 0 0)
			(layers "B.Cu" "B.Mask" "B.Paste")
			(net "H_CPU1_PROCHOT_LVC1_N")
		)
	)
)
